(kicad_pcb
	(version 20241229)
	(generator "pcbnew")
	(generator_version "9.0")
	(general
		(thickness 1.63)
		(legacy_teardrops no)
	)
	(paper "A4")
	(title_block
		(title "CM4 Baseboard")
		(date "2026-01-05")
		(rev "1.1.1")
		(company "Antmicro Ltd")
		(comment 1 "www.antmicro.com")
		(comment 9 "footprints 479-482 of 506")
	)
	(layers
		(0 "F.Cu" signal)
		(4 "In1.Cu" power)
		(6 "In2.Cu" power)
		(8 "In3.Cu" signal)
		(10 "In4.Cu" signal)
		(2 "B.Cu" signal)
		(9 "F.Adhes" user "F.Adhesive")
		(11 "B.Adhes" user "B.Adhesive")
		(13 "F.Paste" user)
		(15 "B.Paste" user)
		(5 "F.SilkS" user "F.Silkscreen")
		(7 "B.SilkS" user "B.Silkscreen")
		(1 "F.Mask" user)
		(3 "B.Mask" user)
		(17 "Dwgs.User" user "User.Drawings")
		(19 "Cmts.User" user "User.Comments")
		(21 "Eco1.User" user "User.Eco1")
		(23 "Eco2.User" user "User.Eco2")
		(25 "Edge.Cuts" user)
		(27 "Margin" user)
		(31 "F.CrtYd" user "F.Courtyard")
		(29 "B.CrtYd" user "B.Courtyard")
		(35 "F.Fab" user)
		(33 "B.Fab" user)
	)
	(footprint "antmicro-footprints:C_0402_1005Metric"
		(layer "B.Cu")
		(at 117.8 173)
		(descr "Capacitor SMD 0402")
		(tags "capacitor SMD 0402")
		(property "Reference" "C828"
			(at -1.341 -1.296 0)
			(layer "B.SilkS")
			(effects
				(font
					(size 0.7 0.7)
					(thickness 0.15)
				)
				(justify right top mirror)
			)
		)
		(property "Value" "C_100n_0402"
			(at -1.022927 -2.155213 0)
			(layer "B.Fab")
			(effects
				(font
					(size 0.7 0.7)
					(thickness 0.15)
				)
				(justify right top mirror)
			)
		)
		(property "Datasheet" "https://www.murata.com/products/productdetail?partno=GRM155R61H104KE14%23"
			(at 0 0 0)
			(layer "B.Fab")
			(hide yes)
			(effects
				(font
					(size 1.27 1.27)
					(thickness 0.15)
				)
				(justify mirror)
			)
		)
		(property "Description" "SMD Multilayer Ceramic Capacitor, 0.1 µF, 50 V, 0402 [1005 Metric], ± 10%, X5R, GRM Series"
			(at 0 0 0)
			(layer "B.Fab")
			(hide yes)
			(effects
				(font
					(size 1.27 1.27)
					(thickness 0.15)
				)
				(justify mirror)
			)
		)
		(property "MPN" "GRM155R61H104KE14D"
			(at 0 0 0)
			(unlocked yes)
			(layer "B.Fab")
			(hide yes)
			(effects
				(font
					(size 1 1)
					(thickness 0.15)
				)
				(justify mirror)
			)
		)
		(property "Manufacturer" "Murata"
			(at 0 0 0)
			(unlocked yes)
			(layer "B.Fab")
			(hide yes)
			(effects
				(font
					(size 1 1)
					(thickness 0.15)
				)
				(justify mirror)
			)
		)
		(property "License" "Apache-2.0"
			(at 0 0 0)
			(unlocked yes)
			(layer "B.Fab")
			(hide yes)
			(effects
				(font
					(size 1 1)
					(thickness 0.15)
				)
				(justify mirror)
			)
		)
		(property "Author" "Antmicro"
			(at 0 0 0)
			(unlocked yes)
			(layer "B.Fab")
			(hide yes)
			(effects
				(font
					(size 1 1)
					(thickness 0.15)
				)
				(justify mirror)
			)
		)
		(property "Val" "100n"
			(at 0 0 0)
			(unlocked yes)
			(layer "B.Fab")
			(hide yes)
			(effects
				(font
					(size 1 1)
					(thickness 0.15)
				)
				(justify mirror)
			)
		)
		(property "Voltage" "50V"
			(at 0 0 0)
			(unlocked yes)
			(layer "B.Fab")
			(hide yes)
			(effects
				(font
					(size 1 1)
					(thickness 0.15)
				)
				(justify mirror)
			)
		)
		(property "Dielectric" "X5R"
			(at 0 0 0)
			(unlocked yes)
			(layer "B.Fab")
			(hide yes)
			(effects
				(font
					(size 1 1)
					(thickness 0.15)
				)
				(justify mirror)
			)
		)
		(sheetname "/Peripherals/")
		(sheetfile "peripherals.kicad_sch")
		(attr smd)
		(fp_rect
			(start -0.925 0.47)
			(end 0.925 -0.47)
			(stroke
				(width 0.05)
				(type default)
			)
			(fill no)
			(layer "B.CrtYd")
		)
		(fp_line
			(start -0.494 -0.248)
			(end -0.494 0.25)
			(stroke
				(width 0.15)
				(type solid)
			)
			(layer "B.Fab")
		)
		(fp_line
			(start -0.494 0.25)
			(end 0.504 0.25)
			(stroke
				(width 0.15)
				(type solid)
			)
			(layer "B.Fab")
		)
		(fp_line
			(start 0.504 -0.248)
			(end -0.494 -0.248)
			(stroke
				(width 0.15)
				(type solid)
			)
			(layer "B.Fab")
		)
		(fp_line
			(start 0.504 0.25)
			(end 0.504 -0.248)
			(stroke
				(width 0.15)
				(type solid)
			)
			(layer "B.Fab")
		)
		(fp_text user "Author: Antmicro"
			(at -0.939 -3.399 0)
			(layer "B.Fab")
			(effects
				(font
					(size 0.7 0.7)
					(thickness 0.15)
				)
				(justify right top mirror)
			)
		)
		(fp_text user "License: Apache-2.0"
			(at -0.939 -5.799 0)
			(layer "B.Fab")
			(effects
				(font
					(size 0.7 0.7)
					(thickness 0.15)
				)
				(justify right top mirror)
			)
		)
		(fp_text user "${REFERENCE}"
			(at -0.939 -4.599 0)
			(layer "B.Fab")
			(effects
				(font
					(size 0.7 0.7)
					(thickness 0.15)
				)
				(justify right top mirror)
			)
		)
		(pad "1" smd roundrect
			(at -0.48 0)
			(size 0.59 0.64)
			(layers "B.Cu" "B.Mask" "B.Paste")
			(roundrect_rratio 0.25)
			(net 9 "+3V3")
			(pintype "passive")
		)
		(pad "2" smd roundrect
			(at 0.48 0)
			(size 0.59 0.64)
			(layers "B.Cu" "B.Mask" "B.Paste")
			(roundrect_rratio 0.25)
			(net 3 "GND")
			(pintype "passive")
		)
	)
	(footprint "antmicro-footprints:R_0402_1005Metric"
		(layer "B.Cu")
		(at 90.387962 153.3915)
		(descr "Resistor SMD 0402")
		(tags "resistor SMD 0402")
		(property "Reference" "R233"
			(at -1.71 3.94 0)
			(layer "B.SilkS")
			(effects
				(font
					(size 0.7 0.7)
					(thickness 0.15)
				)
				(justify right bottom mirror)
			)
		)
		(property "Value" "R_10k_0402"
			(at -1.011843 -1.772047 0)
			(layer "B.Fab")
			(effects
				(font
					(size 0.7 0.7)
					(thickness 0.15)
				)
				(justify right bottom mirror)
			)
		)
		(property "Datasheet" "https://www.bourns.com/docs/product-datasheets/cr.pdf"
			(at 0 0 0)
			(layer "B.Fab")
			(hide yes)
			(effects
				(font
					(size 1.27 1.27)
					(thickness 0.15)
				)
			)
		)
		(property "MPN" "CR0402-FX-1002GLF"
			(at 0 0 0)
			(unlocked yes)
			(layer "B.Fab")
			(hide yes)
			(effects
				(font
					(size 1 1)
					(thickness 0.15)
				)
				(justify mirror)
			)
		)
		(property "Manufacturer" "Bourns"
			(at 0 0 0)
			(unlocked yes)
			(layer "B.Fab")
			(hide yes)
			(effects
				(font
					(size 1 1)
					(thickness 0.15)
				)
				(justify mirror)
			)
		)
		(property "License" "Apache-2.0"
			(at 0 0 0)
			(unlocked yes)
			(layer "B.Fab")
			(hide yes)
			(effects
				(font
					(size 1 1)
					(thickness 0.15)
				)
				(justify mirror)
			)
		)
		(property "Author" "Antmicro"
			(at 0 0 0)
			(unlocked yes)
			(layer "B.Fab")
			(hide yes)
			(effects
				(font
					(size 1 1)
					(thickness 0.15)
				)
				(justify mirror)
			)
		)
		(property "Val" "10k"
			(at 0 0 0)
			(unlocked yes)
			(layer "B.Fab")
			(hide yes)
			(effects
				(font
					(size 1 1)
					(thickness 0.15)
				)
				(justify mirror)
			)
		)
		(property "Tolerance" "1%"
			(at 0 0 0)
			(unlocked yes)
			(layer "B.Fab")
			(hide yes)
			(effects
				(font
					(size 1 1)
					(thickness 0.15)
				)
				(justify mirror)
			)
		)
		(sheetname "/Compute module/")
		(sheetfile "compute-module.kicad_sch")
		(attr smd)
		(fp_rect
			(start -0.925 0.47)
			(end 0.925 -0.47)
			(stroke
				(width 0.05)
				(type default)
			)
			(fill no)
			(layer "B.CrtYd")
		)
		(fp_rect
			(start -0.5 0.25)
			(end 0.5 -0.25)
			(stroke
				(width 0.15)
				(type solid)
			)
			(fill no)
			(layer "B.Fab")
		)
		(fp_text user "License: Apache-2.0"
			(at -0.95 -5.169 180)
			(layer "B.Fab")
			(effects
				(font
					(size 0.7 0.7)
					(thickness 0.15)
				)
				(justify left bottom mirror)
			)
		)
		(fp_text user "${REFERENCE}"
			(at -0.95 -3.168 180)
			(layer "B.Fab")
			(effects
				(font
					(size 0.7 0.7)
					(thickness 0.15)
				)
				(justify left bottom mirror)
			)
		)
		(fp_text user "Author: Antmicro"
			(at -0.95 -4.169 180)
			(layer "B.Fab")
			(effects
				(font
					(size 0.7 0.7)
					(thickness 0.15)
				)
				(justify left bottom mirror)
			)
		)
		(pad "1" smd roundrect
			(at -0.48 0)
			(size 0.59 0.64)
			(layers "B.Cu" "B.Mask" "B.Paste")
			(roundrect_rratio 0.25)
			(net 3 "GND")
			(pintype "passive")
		)
		(pad "2" smd roundrect
			(at 0.48 0)
			(size 0.59 0.64)
			(layers "B.Cu" "B.Mask" "B.Paste")
			(roundrect_rratio 0.25)
			(net 346 "Net-(U204-A1)")
			(pintype "passive")
		)
	)
	(footprint "antmicro-footprints:C_0402_1005Metric"
		(layer "B.Cu")
		(at 66.217962 176.2415 180)
		(descr "Capacitor SMD 0402")
		(tags "capacitor SMD 0402")
		(property "Reference" "C813"
			(at -3.782038 0.545 0)
			(layer "B.SilkS")
			(effects
				(font
					(size 0.7 0.7)
					(thickness 0.15)
				)
				(justify left top mirror)
			)
		)
		(property "Value" "C_1n_0402"
			(at -1.022927 -2.155213 0)
			(layer "B.Fab")
			(effects
				(font
					(size 0.7 0.7)
					(thickness 0.15)
				)
				(justify left top mirror)
			)
		)
		(property "Datasheet" "https://www.murata.com/products/productdetail?partno=GRM1555C1H102JA01%23"
			(at 0 0 0)
			(layer "B.Fab")
			(hide yes)
			(effects
				(font
					(size 1.27 1.27)
					(thickness 0.15)
				)
			)
		)
		(property "Description" "SMD Multilayer Ceramic Capacitor, 1000 pF, 50 V, 0402 [1005 Metric], ± 5%, C0G / NP0, GRM Series"
			(at 0 0 0)
			(layer "B.Fab")
			(hide yes)
			(effects
				(font
					(size 1.27 1.27)
					(thickness 0.15)
				)
			)
		)
		(property "MPN" "GRM1555C1H102JA01D"
			(at 0 0 180)
			(unlocked yes)
			(layer "B.Fab")
			(hide yes)
			(effects
				(font
					(size 1 1)
					(thickness 0.15)
				)
				(justify mirror)
			)
		)
		(property "Manufacturer" "Murata"
			(at 0 0 180)
			(unlocked yes)
			(layer "B.Fab")
			(hide yes)
			(effects
				(font
					(size 1 1)
					(thickness 0.15)
				)
				(justify mirror)
			)
		)
		(property "License" "Apache-2.0"
			(at 0 0 180)
			(unlocked yes)
			(layer "B.Fab")
			(hide yes)
			(effects
				(font
					(size 1 1)
					(thickness 0.15)
				)
				(justify mirror)
			)
		)
		(property "Author" "Antmicro"
			(at 0 0 180)
			(unlocked yes)
			(layer "B.Fab")
			(hide yes)
			(effects
				(font
					(size 1 1)
					(thickness 0.15)
				)
				(justify mirror)
			)
		)
		(property "Val" "1n"
			(at 0 0 180)
			(unlocked yes)
			(layer "B.Fab")
			(hide yes)
			(effects
				(font
					(size 1 1)
					(thickness 0.15)
				)
				(justify mirror)
			)
		)
		(property "Voltage" "50V"
			(at 0 0 180)
			(unlocked yes)
			(layer "B.Fab")
			(hide yes)
			(effects
				(font
					(size 1 1)
					(thickness 0.15)
				)
				(justify mirror)
			)
		)
		(property "Dielectric" "C0G"
			(at 0 0 180)
			(unlocked yes)
			(layer "B.Fab")
			(hide yes)
			(effects
				(font
					(size 1 1)
					(thickness 0.15)
				)
				(justify mirror)
			)
		)
		(sheetname "/Peripherals/")
		(sheetfile "peripherals.kicad_sch")
		(attr smd)
		(fp_rect
			(start -0.925 0.47)
			(end 0.925 -0.47)
			(stroke
				(width 0.05)
				(type default)
			)
			(fill no)
			(layer "B.CrtYd")
		)
		(fp_line
			(start 0.504 0.25)
			(end 0.504 -0.248)
			(stroke
				(width 0.15)
				(type solid)
			)
			(layer "B.Fab")
		)
		(fp_line
			(start 0.504 -0.248)
			(end -0.494 -0.248)
			(stroke
				(width 0.15)
				(type solid)
			)
			(layer "B.Fab")
		)
		(fp_line
			(start -0.494 0.25)
			(end 0.504 0.25)
			(stroke
				(width 0.15)
				(type solid)
			)
			(layer "B.Fab")
		)
		(fp_line
			(start -0.494 -0.248)
			(end -0.494 0.25)
			(stroke
				(width 0.15)
				(type solid)
			)
			(layer "B.Fab")
		)
		(fp_text user "${REFERENCE}"
			(at -0.939 -4.599 0)
			(layer "B.Fab")
			(effects
				(font
					(size 0.7 0.7)
					(thickness 0.15)
				)
				(justify left bottom mirror)
			)
		)
		(fp_text user "License: Apache-2.0"
			(at -0.939 -5.799 0)
			(layer "B.Fab")
			(effects
				(font
					(size 0.7 0.7)
					(thickness 0.15)
				)
				(justify left bottom mirror)
			)
		)
		(fp_text user "Author: Antmicro"
			(at -0.939 -3.399 0)
			(layer "B.Fab")
			(effects
				(font
					(size 0.7 0.7)
					(thickness 0.15)
				)
				(justify left bottom mirror)
			)
		)
		(pad "1" smd roundrect
			(at -0.48 0 180)
			(size 0.59 0.64)
			(layers "B.Cu" "B.Mask" "B.Paste")
			(roundrect_rratio 0.25)
			(net 105 "Net-(U801-RXN)")
			(pintype "passive")
		)
		(pad "2" smd roundrect
			(at 0.48 0 180)
			(size 0.59 0.64)
			(layers "B.Cu" "B.Mask" "B.Paste")
			(roundrect_rratio 0.25)
			(net 104 "Net-(C813-Pad2)")
			(pintype "passive")
		)
	)
	(footprint "antmicro-footprints:R_0402_1005Metric"
		(layer "B.Cu")
		(at 45.332962 165.4375)
		(descr "Resistor SMD 0402")
		(tags "resistor SMD 0402")
		(property "Reference" "R301"
			(at -0.13 1.244 0)
			(layer "B.SilkS")
			(effects
				(font
					(size 0.7 0.7)
					(thickness 0.15)
				)
				(justify right bottom mirror)
			)
		)
		(property "Value" "R_33k_0402"
			(at -1.011843 -1.772047 0)
			(layer "B.Fab")
			(effects
				(font
					(size 0.7 0.7)
					(thickness 0.15)
				)
				(justify right bottom mirror)
			)
		)
		(property "Datasheet" "https://www.bourns.com/docs/product-datasheets/cr.pdf"
			(at 0 0 0)
			(layer "B.Fab")
			(hide yes)
			(effects
				(font
					(size 1.27 1.27)
					(thickness 0.15)
				)
			)
		)
		(property "MPN" "CR0402-FX-3302GLF"
			(at 0 0 0)
			(unlocked yes)
			(layer "B.Fab")
			(hide yes)
			(effects
				(font
					(size 1 1)
					(thickness 0.15)
				)
				(justify mirror)
			)
		)
		(property "Manufacturer" "Bourns"
			(at 0 0 0)
			(unlocked yes)
			(layer "B.Fab")
			(hide yes)
			(effects
				(font
					(size 1 1)
					(thickness 0.15)
				)
				(justify mirror)
			)
		)
		(property "License" "Apache-2.0"
			(at 0 0 0)
			(unlocked yes)
			(layer "B.Fab")
			(hide yes)
			(effects
				(font
					(size 1 1)
					(thickness 0.15)
				)
				(justify mirror)
			)
		)
		(property "Author" "Antmicro"
			(at 0 0 0)
			(unlocked yes)
			(layer "B.Fab")
			(hide yes)
			(effects
				(font
					(size 1 1)
					(thickness 0.15)
				)
				(justify mirror)
			)
		)
		(property "Val" "33k"
			(at 0 0 0)
			(unlocked yes)
			(layer "B.Fab")
			(hide yes)
			(effects
				(font
					(size 1 1)
					(thickness 0.15)
				)
				(justify mirror)
			)
		)
		(property "Tolerance" "1%"
			(at 0 0 0)
			(unlocked yes)
			(layer "B.Fab")
			(hide yes)
			(effects
				(font
					(size 1 1)
					(thickness 0.15)
				)
				(justify mirror)
			)
		)
		(sheetname "/Supply/")
		(sheetfile "supply.kicad_sch")
		(attr smd)
		(fp_rect
			(start -0.925 0.47)
			(end 0.925 -0.47)
			(stroke
				(width 0.05)
				(type default)
			)
			(fill no)
			(layer "B.CrtYd")
		)
		(fp_rect
			(start -0.5 0.25)
			(end 0.5 -0.25)
			(stroke
				(width 0.15)
				(type solid)
			)
			(fill no)
			(layer "B.Fab")
		)
		(fp_text user "${REFERENCE}"
			(at -0.95 -3.168 180)
			(layer "B.Fab")
			(effects
				(font
					(size 0.7 0.7)
					(thickness 0.15)
				)
				(justify left bottom mirror)
			)
		)
		(fp_text user "License: Apache-2.0"
			(at -0.95 -5.169 180)
			(layer "B.Fab")
			(effects
				(font
					(size 0.7 0.7)
					(thickness 0.15)
				)
				(justify left bottom mirror)
			)
		)
		(fp_text user "Author: Antmicro"
			(at -0.95 -4.169 180)
			(layer "B.Fab")
			(effects
				(font
					(size 0.7 0.7)
					(thickness 0.15)
				)
				(justify left bottom mirror)
			)
		)
		(pad "1" smd roundrect
			(at -0.48 0)
			(size 0.59 0.64)
			(layers "B.Cu" "B.Mask" "B.Paste")
			(roundrect_rratio 0.25)
			(net 3 "GND")
			(pintype "passive")
		)
		(pad "2" smd roundrect
			(at 0.48 0)
			(size 0.59 0.64)
			(layers "B.Cu" "B.Mask" "B.Paste")
			(roundrect_rratio 0.25)
			(net 332 "Net-(Q301-REF)")
			(pintype "passive")
		)
	)
)
